# T6G (Grand Teton) — schematic netlist excerpt (pin names and nets, part order shuffled) for the footprints in the layout excerpt that follows; sources: Cadence DE-HDL packaged netlist, KiCad conversion of 04192023_DAF0TMB3IC0_F0TG_MB_C_brd_V02_OCP.brd

R891  Q_RES  10K 5% EMPTY  pkg 0402LF  page 151 : A = SCM_SPARE_1 ; B = GND
PC118_6  Q_CAP  22UF 16V 20% X6S  pkg C0805  page 203 : A = SW_P12V_AUX_PVDDCR_CPU1_P0_FLT ; B = GND
R1445  Q_RES  1K 1% EMPTY  pkg 0201LF  page 276 : A = P1V8_CPU0_RT_1D ; B = JTAG_TDO_RT_CPU0_P0
PC523_2  Q_CAP  22UF 4V 20% X6S  pkg C0805  page 225 : A = PVDD11_S3_P1 ; B = GND

(kicad_pcb
	(version 20260206)
	(generator "pcbnew")
	(generator_version "10.0")
	(general
		(thickness 1.6)
		(legacy_teardrops no)
	)
	(paper "A4")
	(title_block
		(title "04192023_DAF0TMB3IC0_F0TG_MB_C_brd_V02_OCP.brd")
		(comment 1 "Grand Teton / footprints 5542-5545 of 8354")
	)
	(layers
		(0 "F.Cu" signal "TOP")
		(4 "In1.Cu" signal "GND")
		(6 "In2.Cu" signal "IN1")
		(8 "In3.Cu" signal "GND1")
		(10 "In4.Cu" signal "IN2")
		(12 "In5.Cu" signal "GND2")
		(14 "In6.Cu" signal "IN3")
		(16 "In7.Cu" signal "GND3")
		(18 "In8.Cu" signal "VCC")
		(20 "In9.Cu" signal "VCC1")
		(22 "In10.Cu" signal "GND4")
		(24 "In11.Cu" signal "IN4")
		(26 "In12.Cu" signal "GND5")
		(28 "In13.Cu" signal "IN5")
		(30 "In14.Cu" signal "GND6")
		(32 "In15.Cu" signal "IN6")
		(34 "In16.Cu" signal "GND7")
		(2 "B.Cu" signal "BOTTOM")
		(9 "F.Adhes" user "F.Adhesive")
		(11 "B.Adhes" user "B.Adhesive")
		(13 "F.Paste" user "Package Geometry/Pastemask Top")
		(15 "B.Paste" user "Package Geometry/Pastemask Bottom")
		(5 "F.SilkS" user "Ref Des/Silkscreen Top")
		(7 "B.SilkS" user "Ref Des/Silkscreen Bottom")
		(1 "F.Mask" user "Board Geometry/Soldermask Top")
		(3 "B.Mask" user "Board Geometry/Soldermask Bottom")
		(17 "Dwgs.User" user "User.Drawings")
		(19 "Cmts.User" user "User.Comments")
		(21 "Eco1.User" user "User.Eco1")
		(23 "Eco2.User" user "User.Eco2")
		(25 "Edge.Cuts" user "Board Geometry/Outline")
		(27 "Margin" user)
		(31 "F.CrtYd" user "Package Geometry/Place Bound Top")
		(29 "B.CrtYd" user "Package Geometry/Place Bound Bottom")
		(35 "F.Fab" user "Ref Des/Assembly Top")
		(33 "B.Fab" user "Ref Des/Assembly Bottom")
	)
	(footprint ""
		(layer "B.Cu")
		(at 354.915724 -340.002368 90)
		(property "Reference" "PC118_6"
			(at 0 0 90)
			(layer "B.SilkS")
			(hide yes)
			(effects
				(font
					(size 1.27 1.27)
				)
				(justify mirror)
			)
		)
		(property "Value" ""
			(at 0 0 90)
			(layer "B.Fab")
			(effects
				(font
					(size 1.27 1.27)
				)
				(justify mirror)
			)
		)
		(duplicate_pad_numbers_are_jumpers no)
		(fp_line
			(start 1.524 -0.762)
			(end -1.524 -0.762)
			(stroke
				(width 0.1524)
				(type default)
			)
			(layer "B.SilkS")
		)
		(fp_line
			(start -1.524 -0.762)
			(end -1.524 0.762)
			(stroke
				(width 0.1524)
				(type default)
			)
			(layer "B.SilkS")
		)
		(fp_line
			(start 1.524 0.762)
			(end 1.524 -0.762)
			(stroke
				(width 0.1524)
				(type default)
			)
			(layer "B.SilkS")
		)
		(fp_line
			(start -1.524 0.762)
			(end 1.524 0.762)
			(stroke
				(width 0.1524)
				(type default)
			)
			(layer "B.SilkS")
		)
		(fp_line
			(start 1.1049 -0.724916)
			(end 1.1049 0.724916)
			(stroke
				(width 0.1)
				(type default)
			)
			(layer "B.Fab")
		)
		(fp_line
			(start -1.1049 -0.724916)
			(end 1.1049 -0.724916)
			(stroke
				(width 0.1)
				(type default)
			)
			(layer "B.Fab")
		)
		(fp_line
			(start 1.1049 0.724916)
			(end -1.1049 0.724916)
			(stroke
				(width 0.1)
				(type default)
			)
			(layer "B.Fab")
		)
		(fp_line
			(start -1.1049 0.724916)
			(end -1.1049 -0.724916)
			(stroke
				(width 0.1)
				(type default)
			)
			(layer "B.Fab")
		)
		(pad "1" smd rect
			(at 0.889 0 90)
			(size 1.016 1.27)
			(layers "B.Cu" "B.Mask" "B.Paste")
			(net "SW_P12V_AUX_PVDDCR_CPU1_P0_FLT")
		)
		(pad "2" smd rect
			(at -0.889 0 90)
			(size 1.016 1.27)
			(layers "B.Cu" "B.Mask" "B.Paste")
			(net "GND")
		)
	)
	(footprint ""
		(layer "B.Cu")
		(at 305.423316 -426.466 180)
		(property "Reference" "R1445"
			(at 0 0 0)
			(layer "B.SilkS")
			(hide yes)
			(effects
				(font
					(size 1.27 1.27)
				)
				(justify mirror)
			)
		)
		(property "Value" ""
			(at 0 0 0)
			(layer "B.Fab")
			(effects
				(font
					(size 1.27 1.27)
				)
				(justify mirror)
			)
		)
		(duplicate_pad_numbers_are_jumpers no)
		(fp_line
			(start 0.32512 0.175006)
			(end 0.32512 -0.175006)
			(stroke
				(width 0.1)
				(type default)
			)
			(layer "B.Fab")
		)
		(fp_line
			(start 0.32512 -0.175006)
			(end -0.32512 -0.175006)
			(stroke
				(width 0.1)
				(type default)
			)
			(layer "B.Fab")
		)
		(fp_line
			(start -0.32512 0.175006)
			(end 0.32512 0.175006)
			(stroke
				(width 0.1)
				(type default)
			)
			(layer "B.Fab")
		)
		(fp_line
			(start -0.32512 -0.175006)
			(end -0.32512 0.175006)
			(stroke
				(width 0.1)
				(type default)
			)
			(layer "B.Fab")
		)
		(pad "1" smd rect
			(at 0.2667 0)
			(size 0.3048 0.381)
			(layers "B.Cu" "B.Mask" "B.Paste")
			(net "P1V8_CPU0_RT_1D")
		)
		(pad "2" smd rect
			(at -0.2667 0 180)
			(size 0.3048 0.381)
			(layers "B.Cu" "B.Mask" "B.Paste")
			(net "JTAG_TDO_RT_CPU0_P0")
		)
	)
	(footprint ""
		(layer "B.Cu")
		(at 171.196 -118.328948)
		(property "Reference" "R891"
			(at 0 0 0)
			(layer "B.SilkS")
			(hide yes)
			(effects
				(font
					(size 1.27 1.27)
				)
				(justify mirror)
			)
		)
		(property "Value" ""
			(at 0 0 0)
			(layer "B.Fab")
			(effects
				(font
					(size 1.27 1.27)
				)
				(justify mirror)
			)
		)
		(duplicate_pad_numbers_are_jumpers no)
		(fp_line
			(start -0.7874 -0.4064)
			(end -0.7874 0.4064)
			(stroke
				(width 0.1524)
				(type default)
			)
			(layer "B.SilkS")
		)
		(fp_line
			(start -0.7874 0.4064)
			(end 0.7874 0.4064)
			(stroke
				(width 0.1524)
				(type default)
			)
			(layer "B.SilkS")
		)
		(fp_line
			(start 0.7874 -0.4064)
			(end -0.7874 -0.4064)
			(stroke
				(width 0.1524)
				(type default)
			)
			(layer "B.SilkS")
		)
		(fp_line
			(start 0.7874 0.4064)
			(end 0.7874 -0.4064)
			(stroke
				(width 0.1524)
				(type default)
			)
			(layer "B.SilkS")
		)
		(fp_line
			(start -0.67945 -0.3048)
			(end -0.67945 0.3048)
			(stroke
				(width 0.1)
				(type default)
			)
			(layer "B.Fab")
		)
		(fp_line
			(start -0.67945 0.3048)
			(end -0.120396 0.3048)
			(stroke
				(width 0.1)
				(type default)
			)
			(layer "B.Fab")
		)
		(fp_line
			(start -0.12065 -0.3048)
			(end -0.67945 -0.3048)
			(stroke
				(width 0.1)
				(type default)
			)
			(layer "B.Fab")
		)
		(fp_line
			(start -0.12065 -0.2794)
			(end -0.12065 -0.3048)
			(stroke
				(width 0.1)
				(type default)
			)
			(layer "B.Fab")
		)
		(fp_line
			(start -0.120396 0.2794)
			(end 0.12065 0.2794)
			(stroke
				(width 0.1)
				(type default)
			)
			(layer "B.Fab")
		)
		(fp_line
			(start -0.120396 0.3048)
			(end -0.120396 0.2794)
			(stroke
				(width 0.1)
				(type default)
			)
			(layer "B.Fab")
		)
		(fp_line
			(start 0.12065 -0.305054)
			(end 0.12065 -0.2794)
			(stroke
				(width 0.1)
				(type default)
			)
			(layer "B.Fab")
		)
		(fp_line
			(start 0.12065 -0.2794)
			(end -0.12065 -0.2794)
			(stroke
				(width 0.1)
				(type default)
			)
			(layer "B.Fab")
		)
		(fp_line
			(start 0.12065 0.2794)
			(end 0.12065 0.3048)
			(stroke
				(width 0.1)
				(type default)
			)
			(layer "B.Fab")
		)
		(fp_line
			(start 0.12065 0.3048)
			(end 0.67945 0.3048)
			(stroke
				(width 0.1)
				(type default)
			)
			(layer "B.Fab")
		)
		(fp_line
			(start 0.67945 -0.305054)
			(end 0.12065 -0.305054)
			(stroke
				(width 0.1)
				(type default)
			)
			(layer "B.Fab")
		)
		(fp_line
			(start 0.67945 0.3048)
			(end 0.67945 -0.305054)
			(stroke
				(width 0.1)
				(type default)
			)
			(layer "B.Fab")
		)
		(pad "1" smd circle
			(at 0.40005 0 180)
			(size 0 0)
			(layers "B.Cu" "B.Mask" "B.Paste")
			(net "SCM_SPARE_1")
		)
		(pad "2" smd circle
			(at -0.40005 0 180)
			(size 0 0)
			(layers "B.Cu" "B.Mask" "B.Paste")
			(net "GND")
		)
	)
	(footprint ""
		(layer "B.Cu")
		(at 194.67957 -342.10244 -90)
		(property "Reference" "PC523_2"
			(at 0 0 90)
			(layer "B.SilkS")
			(hide yes)
			(effects
				(font
					(size 1.27 1.27)
				)
				(justify mirror)
			)
		)
		(property "Value" ""
			(at 0 0 90)
			(layer "B.Fab")
			(effects
				(font
					(size 1.27 1.27)
				)
				(justify mirror)
			)
		)
		(duplicate_pad_numbers_are_jumpers no)
		(fp_line
			(start -1.524 0.762)
			(end 1.524 0.762)
			(stroke
				(width 0.1524)
				(type default)
			)
			(layer "B.SilkS")
		)
		(fp_line
			(start 1.524 0.762)
			(end 1.524 -0.762)
			(stroke
				(width 0.1524)
				(type default)
			)
			(layer "B.SilkS")
		)
		(fp_line
			(start -1.524 -0.762)
			(end -1.524 0.762)
			(stroke
				(width 0.1524)
				(type default)
			)
			(layer "B.SilkS")
		)
		(fp_line
			(start 1.524 -0.762)
			(end -1.524 -0.762)
			(stroke
				(width 0.1524)
				(type default)
			)
			(layer "B.SilkS")
		)
		(fp_line
			(start -1.1049 0.724916)
			(end -1.1049 -0.724916)
			(stroke
				(width 0.1)
				(type default)
			)
			(layer "B.Fab")
		)
		(fp_line
			(start 1.1049 0.724916)
			(end -1.1049 0.724916)
			(stroke
				(width 0.1)
				(type default)
			)
			(layer "B.Fab")
		)
		(fp_line
			(start -1.1049 -0.724916)
			(end 1.1049 -0.724916)
			(stroke
				(width 0.1)
				(type default)
			)
			(layer "B.Fab")
		)
		(fp_line
			(start 1.1049 -0.724916)
			(end 1.1049 0.724916)
			(stroke
				(width 0.1)
				(type default)
			)
			(layer "B.Fab")
		)
		(pad "1" smd rect
			(at 0.889 0 270)
			(size 1.016 1.27)
			(layers "B.Cu" "B.Mask" "B.Paste")
			(net "PVDD11_S3_P1")
		)
		(pad "2" smd rect
			(at -0.889 0 270)
			(size 1.016 1.27)
			(layers "B.Cu" "B.Mask" "B.Paste")
			(net "GND")
		)
	)
)
